(kicad_pcb
	(version 20260206)
	(generator "pcbnew")
	(generator_version "10.0")
	(general
		(thickness 1.6)
		(legacy_teardrops no)
	)
	(paper "A4")
	(title_block
		(title "01162023_DA0F0TEBIF0_F0T_Expander_BD_F_brd_V02_OCP.brd")
		(comment 1 "Grand Teton / footprints 1295-1302 of 9728")
	)
	(layers
		(0 "F.Cu" signal "TOP")
		(4 "In1.Cu" signal "GND")
		(6 "In2.Cu" signal "VCC")
		(8 "In3.Cu" signal "VCC1")
		(10 "In4.Cu" signal "GND1")
		(12 "In5.Cu" signal "IN1")
		(14 "In6.Cu" signal "GND2")
		(16 "In7.Cu" signal "IN2")
		(18 "In8.Cu" signal "GND3")
		(20 "In9.Cu" signal "IN3")
		(22 "In10.Cu" signal "GND4")
		(24 "In11.Cu" signal "IN4")
		(26 "In12.Cu" signal "GND5")
		(28 "In13.Cu" signal "IN5")
		(30 "In14.Cu" signal "GND6")
		(32 "In15.Cu" signal "IN6")
		(34 "In16.Cu" signal "GND7")
		(2 "B.Cu" signal "BOTTOM")
		(9 "F.Adhes" user "F.Adhesive")
		(11 "B.Adhes" user "B.Adhesive")
		(13 "F.Paste" user "Package Geometry/Pastemask Top")
		(15 "B.Paste" user "Package Geometry/Pastemask Bottom")
		(5 "F.SilkS" user "Ref Des/Silkscreen Top")
		(7 "B.SilkS" user "Ref Des/Silkscreen Bottom")
		(1 "F.Mask" user "Board Geometry/Soldermask Top")
		(3 "B.Mask" user "Board Geometry/Soldermask Bottom")
		(17 "Dwgs.User" user "User.Drawings")
		(19 "Cmts.User" user "User.Comments")
		(21 "Eco1.User" user "User.Eco1")
		(23 "Eco2.User" user "User.Eco2")
		(25 "Edge.Cuts" user "Board Geometry/Outline")
		(27 "Margin" user)
		(31 "F.CrtYd" user "Package Geometry/Place Bound Top")
		(29 "B.CrtYd" user "Package Geometry/Place Bound Bottom")
		(35 "F.Fab" user "Ref Des/Assembly Top")
		(33 "B.Fab" user "Ref Des/Assembly Bottom")
	)
	(footprint ""
		(layer "F.Cu")
		(at 327.533 -240.157 90)
		(property "Reference" "R1782"
			(at 0 0 90)
			(layer "F.SilkS")
			(hide yes)
			(effects
				(font
					(size 1.27 1.27)
				)
			)
		)
		(property "Value" ""
			(at 0 0 90)
			(layer "F.Fab")
			(effects
				(font
					(size 1.27 1.27)
				)
			)
		)
		(duplicate_pad_numbers_are_jumpers no)
		(fp_line
			(start 0.7874 -0.4064)
			(end 0.7874 0.4064)
			(stroke
				(width 0.1524)
				(type default)
			)
			(layer "F.SilkS")
		)
		(fp_line
			(start -0.7874 -0.4064)
			(end 0.7874 -0.4064)
			(stroke
				(width 0.1524)
				(type default)
			)
			(layer "F.SilkS")
		)
		(fp_line
			(start 0.7874 0.4064)
			(end -0.7874 0.4064)
			(stroke
				(width 0.1524)
				(type default)
			)
			(layer "F.SilkS")
		)
		(fp_line
			(start -0.7874 0.4064)
			(end -0.7874 -0.4064)
			(stroke
				(width 0.1524)
				(type default)
			)
			(layer "F.SilkS")
		)
		(fp_line
			(start -0.12065 -0.305054)
			(end -0.12065 -0.2794)
			(stroke
				(width 0.1)
				(type default)
			)
			(layer "F.Fab")
		)
		(fp_line
			(start -0.67945 -0.305054)
			(end -0.12065 -0.305054)
			(stroke
				(width 0.1)
				(type default)
			)
			(layer "F.Fab")
		)
		(fp_line
			(start 0.67945 -0.3048)
			(end 0.67945 0.3048)
			(stroke
				(width 0.1)
				(type default)
			)
			(layer "F.Fab")
		)
		(fp_line
			(start 0.12065 -0.3048)
			(end 0.67945 -0.3048)
			(stroke
				(width 0.1)
				(type default)
			)
			(layer "F.Fab")
		)
		(fp_line
			(start 0.12065 -0.2794)
			(end 0.12065 -0.3048)
			(stroke
				(width 0.1)
				(type default)
			)
			(layer "F.Fab")
		)
		(fp_line
			(start -0.12065 -0.2794)
			(end 0.12065 -0.2794)
			(stroke
				(width 0.1)
				(type default)
			)
			(layer "F.Fab")
		)
		(fp_line
			(start 0.120396 0.2794)
			(end -0.12065 0.2794)
			(stroke
				(width 0.1)
				(type default)
			)
			(layer "F.Fab")
		)
		(fp_line
			(start -0.12065 0.2794)
			(end -0.12065 0.3048)
			(stroke
				(width 0.1)
				(type default)
			)
			(layer "F.Fab")
		)
		(fp_line
			(start 0.67945 0.3048)
			(end 0.120396 0.3048)
			(stroke
				(width 0.1)
				(type default)
			)
			(layer "F.Fab")
		)
		(fp_line
			(start 0.120396 0.3048)
			(end 0.120396 0.2794)
			(stroke
				(width 0.1)
				(type default)
			)
			(layer "F.Fab")
		)
		(fp_line
			(start -0.12065 0.3048)
			(end -0.67945 0.3048)
			(stroke
				(width 0.1)
				(type default)
			)
			(layer "F.Fab")
		)
		(fp_line
			(start -0.67945 0.3048)
			(end -0.67945 -0.305054)
			(stroke
				(width 0.1)
				(type default)
			)
			(layer "F.Fab")
		)
		(pad "1" smd circle
			(at -0.40005 0 90)
			(size 0 0)
			(layers "F.Cu" "F.Mask" "F.Paste")
			(net "PRSNT_GPU_ISO")
		)
		(pad "2" smd circle
			(at 0.40005 0 90)
			(size 0 0)
			(layers "F.Cu" "F.Mask" "F.Paste")
			(net "P3V3_AUX")
		)
	)
	(footprint ""
		(layer "F.Cu")
		(at 215.630506 -66.32194 -90)
		(property "Reference" "PC857"
			(at 0 0 270)
			(layer "F.SilkS")
			(hide yes)
			(effects
				(font
					(size 1.27 1.27)
				)
			)
		)
		(property "Value" ""
			(at 0 0 270)
			(layer "F.Fab")
			(effects
				(font
					(size 1.27 1.27)
				)
			)
		)
		(duplicate_pad_numbers_are_jumpers no)
		(fp_line
			(start -0.7874 0.4064)
			(end -0.7874 -0.4064)
			(stroke
				(width 0.1524)
				(type default)
			)
			(layer "F.SilkS")
		)
		(fp_line
			(start 0.7874 0.4064)
			(end -0.7874 0.4064)
			(stroke
				(width 0.1524)
				(type default)
			)
			(layer "F.SilkS")
		)
		(fp_line
			(start -0.7874 -0.4064)
			(end 0.7874 -0.4064)
			(stroke
				(width 0.1524)
				(type default)
			)
			(layer "F.SilkS")
		)
		(fp_line
			(start 0.7874 -0.4064)
			(end 0.7874 0.4064)
			(stroke
				(width 0.1524)
				(type default)
			)
			(layer "F.SilkS")
		)
		(fp_line
			(start -0.67945 0.3048)
			(end -0.67945 -0.305054)
			(stroke
				(width 0.1)
				(type default)
			)
			(layer "F.Fab")
		)
		(fp_line
			(start -0.12065 0.3048)
			(end -0.67945 0.3048)
			(stroke
				(width 0.1)
				(type default)
			)
			(layer "F.Fab")
		)
		(fp_line
			(start 0.120396 0.3048)
			(end 0.120396 0.2794)
			(stroke
				(width 0.1)
				(type default)
			)
			(layer "F.Fab")
		)
		(fp_line
			(start 0.67945 0.3048)
			(end 0.120396 0.3048)
			(stroke
				(width 0.1)
				(type default)
			)
			(layer "F.Fab")
		)
		(fp_line
			(start -0.12065 0.2794)
			(end -0.12065 0.3048)
			(stroke
				(width 0.1)
				(type default)
			)
			(layer "F.Fab")
		)
		(fp_line
			(start 0.120396 0.2794)
			(end -0.12065 0.2794)
			(stroke
				(width 0.1)
				(type default)
			)
			(layer "F.Fab")
		)
		(fp_line
			(start -0.12065 -0.2794)
			(end 0.12065 -0.2794)
			(stroke
				(width 0.1)
				(type default)
			)
			(layer "F.Fab")
		)
		(fp_line
			(start 0.12065 -0.2794)
			(end 0.12065 -0.3048)
			(stroke
				(width 0.1)
				(type default)
			)
			(layer "F.Fab")
		)
		(fp_line
			(start 0.12065 -0.3048)
			(end 0.67945 -0.3048)
			(stroke
				(width 0.1)
				(type default)
			)
			(layer "F.Fab")
		)
		(fp_line
			(start 0.67945 -0.3048)
			(end 0.67945 0.3048)
			(stroke
				(width 0.1)
				(type default)
			)
			(layer "F.Fab")
		)
		(fp_line
			(start -0.67945 -0.305054)
			(end -0.12065 -0.305054)
			(stroke
				(width 0.1)
				(type default)
			)
			(layer "F.Fab")
		)
		(fp_line
			(start -0.12065 -0.305054)
			(end -0.12065 -0.2794)
			(stroke
				(width 0.1)
				(type default)
			)
			(layer "F.Fab")
		)
		(pad "1" smd circle
			(at -0.40005 0 270)
			(size 0 0)
			(layers "F.Cu" "F.Mask" "F.Paste")
			(net "P12V_SSD7_CO_DV_DT")
		)
		(pad "2" smd circle
			(at 0.40005 0 270)
			(size 0 0)
			(layers "F.Cu" "F.Mask" "F.Paste")
			(net "GND")
		)
	)
	(footprint ""
		(layer "F.Cu")
		(at 482.92893 -526.47723 180)
		(property "Reference" "J37_OTH"
			(at -3.2385 -1.402334 0)
			(unlocked yes)
			(layer "B.SilkS")
			(effects
				(font
					(size 0.7874 0.5842)
					(thickness 0.1524)
				)
				(justify mirror)
			)
		)
		(property "Value" ""
			(at 0 0 180)
			(layer "F.Fab")
			(effects
				(font
					(size 1.27 1.27)
				)
			)
		)
		(duplicate_pad_numbers_are_jumpers no)
		(pad "1" thru_hole circle
			(at 0 0 180)
			(size 0.4572 0.4572)
			(drill 0.2032)
			(layers "*.Cu" "*.Mask")
			(remove_unused_layers no)
			(net "Net_9099")
			(clearance 0.127)
			(thermal_gap 0.127)
			(padstack
				(mode front_inner_back)
				(layer "Inner"
					(shape circle)
					(size 0.4572 0.4572)
					(clearance 0.127)
				)
				(layer "B.Cu"
					(shape circle)
					(size 0.508 0.508)
					(clearance 0.1016)
				)
			)
		)
	)
	(footprint ""
		(layer "F.Cu")
		(at 401.426172 -37.929566 90)
		(property "Reference" "R5579"
			(at 0 0 90)
			(layer "F.SilkS")
			(hide yes)
			(effects
				(font
					(size 1.27 1.27)
				)
			)
		)
		(property "Value" ""
			(at 0 0 90)
			(layer "F.Fab")
			(effects
				(font
					(size 1.27 1.27)
				)
			)
		)
		(duplicate_pad_numbers_are_jumpers no)
		(fp_line
			(start 0.7874 -0.4064)
			(end 0.7874 0.4064)
			(stroke
				(width 0.1524)
				(type default)
			)
			(layer "F.SilkS")
		)
		(fp_line
			(start -0.7874 -0.4064)
			(end 0.7874 -0.4064)
			(stroke
				(width 0.1524)
				(type default)
			)
			(layer "F.SilkS")
		)
		(fp_line
			(start 0.7874 0.4064)
			(end -0.7874 0.4064)
			(stroke
				(width 0.1524)
				(type default)
			)
			(layer "F.SilkS")
		)
		(fp_line
			(start -0.7874 0.4064)
			(end -0.7874 -0.4064)
			(stroke
				(width 0.1524)
				(type default)
			)
			(layer "F.SilkS")
		)
		(fp_line
			(start -0.12065 -0.305054)
			(end -0.12065 -0.2794)
			(stroke
				(width 0.1)
				(type default)
			)
			(layer "F.Fab")
		)
		(fp_line
			(start -0.67945 -0.305054)
			(end -0.12065 -0.305054)
			(stroke
				(width 0.1)
				(type default)
			)
			(layer "F.Fab")
		)
		(fp_line
			(start 0.67945 -0.3048)
			(end 0.67945 0.3048)
			(stroke
				(width 0.1)
				(type default)
			)
			(layer "F.Fab")
		)
		(fp_line
			(start 0.12065 -0.3048)
			(end 0.67945 -0.3048)
			(stroke
				(width 0.1)
				(type default)
			)
			(layer "F.Fab")
		)
		(fp_line
			(start 0.12065 -0.2794)
			(end 0.12065 -0.3048)
			(stroke
				(width 0.1)
				(type default)
			)
			(layer "F.Fab")
		)
		(fp_line
			(start -0.12065 -0.2794)
			(end 0.12065 -0.2794)
			(stroke
				(width 0.1)
				(type default)
			)
			(layer "F.Fab")
		)
		(fp_line
			(start 0.120396 0.2794)
			(end -0.12065 0.2794)
			(stroke
				(width 0.1)
				(type default)
			)
			(layer "F.Fab")
		)
		(fp_line
			(start -0.12065 0.2794)
			(end -0.12065 0.3048)
			(stroke
				(width 0.1)
				(type default)
			)
			(layer "F.Fab")
		)
		(fp_line
			(start 0.67945 0.3048)
			(end 0.120396 0.3048)
			(stroke
				(width 0.1)
				(type default)
			)
			(layer "F.Fab")
		)
		(fp_line
			(start 0.120396 0.3048)
			(end 0.120396 0.2794)
			(stroke
				(width 0.1)
				(type default)
			)
			(layer "F.Fab")
		)
		(fp_line
			(start -0.12065 0.3048)
			(end -0.67945 0.3048)
			(stroke
				(width 0.1)
				(type default)
			)
			(layer "F.Fab")
		)
		(fp_line
			(start -0.67945 0.3048)
			(end -0.67945 -0.305054)
			(stroke
				(width 0.1)
				(type default)
			)
			(layer "F.Fab")
		)
		(pad "1" smd circle
			(at -0.40005 0 90)
			(size 0 0)
			(layers "F.Cu" "F.Mask" "F.Paste")
			(net "SSD14_AUX_P3V3_EN_R")
		)
		(pad "2" smd circle
			(at 0.40005 0 90)
			(size 0 0)
			(layers "F.Cu" "F.Mask" "F.Paste")
			(net "SSD14_AUX_P3V3_EN")
		)
	)
	(footprint ""
		(layer "F.Cu")
		(at 96.722438 -44.341542 90)
		(property "Reference" "R547"
			(at 0 0 90)
			(layer "F.SilkS")
			(hide yes)
			(effects
				(font
					(size 1.27 1.27)
				)
			)
		)
		(property "Value" ""
			(at 0 0 90)
			(layer "F.Fab")
			(effects
				(font
					(size 1.27 1.27)
				)
			)
		)
		(duplicate_pad_numbers_are_jumpers no)
		(fp_line
			(start 0.7874 -0.4064)
			(end 0.7874 0.4064)
			(stroke
				(width 0.1524)
				(type default)
			)
			(layer "F.SilkS")
		)
		(fp_line
			(start -0.7874 -0.4064)
			(end 0.7874 -0.4064)
			(stroke
				(width 0.1524)
				(type default)
			)
			(layer "F.SilkS")
		)
		(fp_line
			(start 0.7874 0.4064)
			(end -0.7874 0.4064)
			(stroke
				(width 0.1524)
				(type default)
			)
			(layer "F.SilkS")
		)
		(fp_line
			(start -0.7874 0.4064)
			(end -0.7874 -0.4064)
			(stroke
				(width 0.1524)
				(type default)
			)
			(layer "F.SilkS")
		)
		(fp_line
			(start -0.12065 -0.305054)
			(end -0.12065 -0.2794)
			(stroke
				(width 0.1)
				(type default)
			)
			(layer "F.Fab")
		)
		(fp_line
			(start -0.67945 -0.305054)
			(end -0.12065 -0.305054)
			(stroke
				(width 0.1)
				(type default)
			)
			(layer "F.Fab")
		)
		(fp_line
			(start 0.67945 -0.3048)
			(end 0.67945 0.3048)
			(stroke
				(width 0.1)
				(type default)
			)
			(layer "F.Fab")
		)
		(fp_line
			(start 0.12065 -0.3048)
			(end 0.67945 -0.3048)
			(stroke
				(width 0.1)
				(type default)
			)
			(layer "F.Fab")
		)
		(fp_line
			(start 0.12065 -0.2794)
			(end 0.12065 -0.3048)
			(stroke
				(width 0.1)
				(type default)
			)
			(layer "F.Fab")
		)
		(fp_line
			(start -0.12065 -0.2794)
			(end 0.12065 -0.2794)
			(stroke
				(width 0.1)
				(type default)
			)
			(layer "F.Fab")
		)
		(fp_line
			(start 0.120396 0.2794)
			(end -0.12065 0.2794)
			(stroke
				(width 0.1)
				(type default)
			)
			(layer "F.Fab")
		)
		(fp_line
			(start -0.12065 0.2794)
			(end -0.12065 0.3048)
			(stroke
				(width 0.1)
				(type default)
			)
			(layer "F.Fab")
		)
		(fp_line
			(start 0.67945 0.3048)
			(end 0.120396 0.3048)
			(stroke
				(width 0.1)
				(type default)
			)
			(layer "F.Fab")
		)
		(fp_line
			(start 0.120396 0.3048)
			(end 0.120396 0.2794)
			(stroke
				(width 0.1)
				(type default)
			)
			(layer "F.Fab")
		)
		(fp_line
			(start -0.12065 0.3048)
			(end -0.67945 0.3048)
			(stroke
				(width 0.1)
				(type default)
			)
			(layer "F.Fab")
		)
		(fp_line
			(start -0.67945 0.3048)
			(end -0.67945 -0.305054)
			(stroke
				(width 0.1)
				(type default)
			)
			(layer "F.Fab")
		)
		(pad "1" smd circle
			(at -0.40005 0 90)
			(size 0 0)
			(layers "F.Cu" "F.Mask" "F.Paste")
			(net "P12V_SSD3")
		)
		(pad "2" smd circle
			(at 0.40005 0 90)
			(size 0 0)
			(layers "F.Cu" "F.Mask" "F.Paste")
			(net "P12V_SSD3_VIN_N")
		)
	)
	(footprint ""
		(layer "F.Cu")
		(at 215.047322 -20.35556)
		(property "Reference" "C3922"
			(at 0 0 0)
			(layer "F.SilkS")
			(hide yes)
			(effects
				(font
					(size 1.27 1.27)
				)
			)
		)
		(property "Value" ""
			(at 0 0 0)
			(layer "F.Fab")
			(effects
				(font
					(size 1.27 1.27)
				)
			)
		)
		(duplicate_pad_numbers_are_jumpers no)
		(fp_line
			(start -0.7874 -0.4064)
			(end 0.7874 -0.4064)
			(stroke
				(width 0.1524)
				(type default)
			)
			(layer "F.SilkS")
		)
		(fp_line
			(start -0.7874 0.4064)
			(end -0.7874 -0.4064)
			(stroke
				(width 0.1524)
				(type default)
			)
			(layer "F.SilkS")
		)
		(fp_line
			(start 0.7874 -0.4064)
			(end 0.7874 0.4064)
			(stroke
				(width 0.1524)
				(type default)
			)
			(layer "F.SilkS")
		)
		(fp_line
			(start 0.7874 0.4064)
			(end -0.7874 0.4064)
			(stroke
				(width 0.1524)
				(type default)
			)
			(layer "F.SilkS")
		)
		(fp_line
			(start -0.67945 -0.305054)
			(end -0.12065 -0.305054)
			(stroke
				(width 0.1)
				(type default)
			)
			(layer "F.Fab")
		)
		(fp_line
			(start -0.67945 0.3048)
			(end -0.67945 -0.305054)
			(stroke
				(width 0.1)
				(type default)
			)
			(layer "F.Fab")
		)
		(fp_line
			(start -0.12065 -0.305054)
			(end -0.12065 -0.2794)
			(stroke
				(width 0.1)
				(type default)
			)
			(layer "F.Fab")
		)
		(fp_line
			(start -0.12065 -0.2794)
			(end 0.12065 -0.2794)
			(stroke
				(width 0.1)
				(type default)
			)
			(layer "F.Fab")
		)
		(fp_line
			(start -0.12065 0.2794)
			(end -0.12065 0.3048)
			(stroke
				(width 0.1)
				(type default)
			)
			(layer "F.Fab")
		)
		(fp_line
			(start -0.12065 0.3048)
			(end -0.67945 0.3048)
			(stroke
				(width 0.1)
				(type default)
			)
			(layer "F.Fab")
		)
		(fp_line
			(start 0.120396 0.2794)
			(end -0.12065 0.2794)
			(stroke
				(width 0.1)
				(type default)
			)
			(layer "F.Fab")
		)
		(fp_line
			(start 0.120396 0.3048)
			(end 0.120396 0.2794)
			(stroke
				(width 0.1)
				(type default)
			)
			(layer "F.Fab")
		)
		(fp_line
			(start 0.12065 -0.3048)
			(end 0.67945 -0.3048)
			(stroke
				(width 0.1)
				(type default)
			)
			(layer "F.Fab")
		)
		(fp_line
			(start 0.12065 -0.2794)
			(end 0.12065 -0.3048)
			(stroke
				(width 0.1)
				(type default)
			)
			(layer "F.Fab")
		)
		(fp_line
			(start 0.67945 -0.3048)
			(end 0.67945 0.3048)
			(stroke
				(width 0.1)
				(type default)
			)
			(layer "F.Fab")
		)
		(fp_line
			(start 0.67945 0.3048)
			(end 0.120396 0.3048)
			(stroke
				(width 0.1)
				(type default)
			)
			(layer "F.Fab")
		)
		(pad "1" smd circle
			(at -0.40005 0)
			(size 0 0)
			(layers "F.Cu" "F.Mask" "F.Paste")
			(net "P12V_SSD7")
		)
		(pad "2" smd circle
			(at 0.40005 0)
			(size 0 0)
			(layers "F.Cu" "F.Mask" "F.Paste")
			(net "GND")
		)
	)
	(footprint ""
		(layer "F.Cu")
		(at 344.612976 -86.169754 180)
		(property "Reference" "R1179"
			(at 0 0 180)
			(layer "F.SilkS")
			(hide yes)
			(effects
				(font
					(size 1.27 1.27)
				)
			)
		)
		(property "Value" ""
			(at 0 0 180)
			(layer "F.Fab")
			(effects
				(font
					(size 1.27 1.27)
				)
			)
		)
		(duplicate_pad_numbers_are_jumpers no)
		(fp_line
			(start 0.7874 0.4064)
			(end -0.7874 0.4064)
			(stroke
				(width 0.1524)
				(type default)
			)
			(layer "F.SilkS")
		)
		(fp_line
			(start 0.67945 0.3048)
			(end 0.120396 0.3048)
			(stroke
				(width 0.1)
				(type default)
			)
			(layer "F.Fab")
		)
		(fp_line
			(start 0.67945 -0.3048)
			(end 0.67945 0.3048)
			(stroke
				(width 0.1)
				(type default)
			)
			(layer "F.Fab")
		)
		(fp_line
			(start 0.12065 -0.2794)
			(end 0.12065 -0.3048)
			(stroke
				(width 0.1)
				(type default)
			)
			(layer "F.Fab")
		)
		(fp_line
			(start 0.12065 -0.3048)
			(end 0.67945 -0.3048)
			(stroke
				(width 0.1)
				(type default)
			)
			(layer "F.Fab")
		)
		(fp_line
			(start 0.120396 0.3048)
			(end 0.120396 0.2794)
			(stroke
				(width 0.1)
				(type default)
			)
			(layer "F.Fab")
		)
		(fp_line
			(start 0.120396 0.2794)
			(end -0.12065 0.2794)
			(stroke
				(width 0.1)
				(type default)
			)
			(layer "F.Fab")
		)
		(fp_line
			(start -0.12065 0.3048)
			(end -0.67945 0.3048)
			(stroke
				(width 0.1)
				(type default)
			)
			(layer "F.Fab")
		)
		(fp_line
			(start -0.12065 0.2794)
			(end -0.12065 0.3048)
			(stroke
				(width 0.1)
				(type default)
			)
			(layer "F.Fab")
		)
		(fp_line
			(start -0.12065 -0.2794)
			(end 0.12065 -0.2794)
			(stroke
				(width 0.1)
				(type default)
			)
			(layer "F.Fab")
		)
		(fp_line
			(start -0.12065 -0.305054)
			(end -0.12065 -0.2794)
			(stroke
				(width 0.1)
				(type default)
			)
			(layer "F.Fab")
		)
		(fp_line
			(start -0.67945 0.3048)
			(end -0.67945 -0.305054)
			(stroke
				(width 0.1)
				(type default)
			)
			(layer "F.Fab")
		)
		(fp_line
			(start -0.67945 -0.305054)
			(end -0.12065 -0.305054)
			(stroke
				(width 0.1)
				(type default)
			)
			(layer "F.Fab")
		)
		(pad "1" smd circle
			(at -0.40005 0 180)
			(size 0 0)
			(layers "F.Cu" "F.Mask" "F.Paste")
			(net "CLK_100M_DB800ZL_SSD12_R_DN")
		)
		(pad "2" smd circle
			(at 0.40005 0 180)
			(size 0 0)
			(layers "F.Cu" "F.Mask" "F.Paste")
			(net "CLK_100M_DB800ZL_SSD12_DN")
		)
	)
	(footprint ""
		(layer "F.Cu")
		(at 489.627164 -525.080992 180)
		(property "Reference" "PEX3_HS"
			(at 0.127 -0.593598 0)
			(unlocked yes)
			(layer "F.SilkS")
			(effects
				(font
					(size 0.254 0.127)
					(thickness 0.000001)
				)
			)
		)
		(property "Value" ""
			(at 0 0 180)
			(layer "F.Fab")
			(effects
				(font
					(size 1.27 1.27)
				)
			)
		)
		(duplicate_pad_numbers_are_jumpers no)
		(pad "1" smd circle
			(at 0 0 180)
			(size 0.762 0.762)
			(layers "F.Cu" "F.Mask" "F.Paste")
			(net "Net_9121")
		)
	)
)
